(kicad_pcb
	(version 20260206)
	(generator "pcbnew")
	(generator_version "10.0")
	(general
		(thickness 1.6)
		(legacy_teardrops no)
	)
	(paper "A4")
	(title_block
		(title "04192023_DAF0TMB3IC0_F0TG_MB_C_brd_V02_OCP.brd")
		(comment 1 "Grand Teton / footprints 6496-6503 of 8354")
	)
	(layers
		(0 "F.Cu" signal "TOP")
		(4 "In1.Cu" signal "GND")
		(6 "In2.Cu" signal "IN1")
		(8 "In3.Cu" signal "GND1")
		(10 "In4.Cu" signal "IN2")
		(12 "In5.Cu" signal "GND2")
		(14 "In6.Cu" signal "IN3")
		(16 "In7.Cu" signal "GND3")
		(18 "In8.Cu" signal "VCC")
		(20 "In9.Cu" signal "VCC1")
		(22 "In10.Cu" signal "GND4")
		(24 "In11.Cu" signal "IN4")
		(26 "In12.Cu" signal "GND5")
		(28 "In13.Cu" signal "IN5")
		(30 "In14.Cu" signal "GND6")
		(32 "In15.Cu" signal "IN6")
		(34 "In16.Cu" signal "GND7")
		(2 "B.Cu" signal "BOTTOM")
		(9 "F.Adhes" user "F.Adhesive")
		(11 "B.Adhes" user "B.Adhesive")
		(13 "F.Paste" user "Package Geometry/Pastemask Top")
		(15 "B.Paste" user "Package Geometry/Pastemask Bottom")
		(5 "F.SilkS" user "Ref Des/Silkscreen Top")
		(7 "B.SilkS" user "Ref Des/Silkscreen Bottom")
		(1 "F.Mask" user "Board Geometry/Soldermask Top")
		(3 "B.Mask" user "Board Geometry/Soldermask Bottom")
		(17 "Dwgs.User" user "User.Drawings")
		(19 "Cmts.User" user "User.Comments")
		(21 "Eco1.User" user "User.Eco1")
		(23 "Eco2.User" user "User.Eco2")
		(25 "Edge.Cuts" user "Board Geometry/Outline")
		(27 "Margin" user)
		(31 "F.CrtYd" user "Package Geometry/Place Bound Top")
		(29 "B.CrtYd" user "Package Geometry/Place Bound Bottom")
		(35 "F.Fab" user "Ref Des/Assembly Top")
		(33 "B.Fab" user "Ref Des/Assembly Bottom")
	)
	(footprint ""
		(layer "B.Cu")
		(at 397.332962 -316.652148 90)
		(property "Reference" "Y2"
			(at 2.936748 0.993648 0)
			(unlocked yes)
			(layer "B.SilkS")
			(effects
				(font
					(size 0.7874 0.5842)
					(thickness 0.1524)
				)
				(justify left mirror)
			)
		)
		(property "Value" ""
			(at 0 0 90)
			(layer "B.Fab")
			(effects
				(font
					(size 1.27 1.27)
				)
				(justify mirror)
			)
		)
		(duplicate_pad_numbers_are_jumpers no)
		(fp_line
			(start 1.538732 -1.937004)
			(end -1.538732 -1.937004)
			(stroke
				(width 0.1524)
				(type default)
			)
			(layer "B.SilkS")
		)
		(fp_line
			(start -1.538732 -1.937004)
			(end -1.538732 1.937004)
			(stroke
				(width 0.1524)
				(type default)
			)
			(layer "B.SilkS")
		)
		(fp_line
			(start 1.538732 1.937004)
			(end 1.538732 -1.937004)
			(stroke
				(width 0.1524)
				(type default)
			)
			(layer "B.SilkS")
		)
		(fp_line
			(start -1.538732 1.937004)
			(end 1.538732 1.937004)
			(stroke
				(width 0.1524)
				(type default)
			)
			(layer "B.SilkS")
		)
		(fp_poly
			(pts
				(xy 1.724406 -1.059942) (xy 2.5908 -1.493266) (xy 2.5908 -0.626872)
			)
			(stroke
				(width 0)
				(type default)
			)
			(fill yes)
			(layer "B.SilkS")
		)
		(fp_line
			(start 1.299972 -1.649984)
			(end -1.299972 -1.649984)
			(stroke
				(width 0.1)
				(type default)
			)
			(layer "B.Fab")
		)
		(fp_line
			(start -1.299972 -1.649984)
			(end -1.299972 1.649984)
			(stroke
				(width 0.1)
				(type default)
			)
			(layer "B.Fab")
		)
		(fp_line
			(start 1.299972 1.649984)
			(end 1.299972 -1.649984)
			(stroke
				(width 0.1)
				(type default)
			)
			(layer "B.Fab")
		)
		(fp_line
			(start -1.299972 1.649984)
			(end 1.299972 1.649984)
			(stroke
				(width 0.1)
				(type default)
			)
			(layer "B.Fab")
		)
		(fp_poly
			(pts
				(xy 2.5908 -0.626872) (xy 2.5908 -1.493266) (xy 1.724406 -1.059942)
			)
			(stroke
				(width 0)
				(type default)
			)
			(fill yes)
			(layer "B.Fab")
		)
		(pad "1" smd rect
			(at 0.8001 -1.059942 270)
			(size 1.2192 1.4986)
			(layers "B.Cu" "B.Mask" "B.Paste")
			(net "XTAL_CPU0_X48M_X1")
		)
		(pad "2" smd rect
			(at 0.8001 1.059942 270)
			(size 1.2192 1.4986)
			(layers "B.Cu" "B.Mask" "B.Paste")
			(net "GND")
		)
		(pad "3" smd rect
			(at -0.8001 1.059942 270)
			(size 1.2192 1.4986)
			(layers "B.Cu" "B.Mask" "B.Paste")
			(net "XTAL_CPU0_X48M_X2_R")
		)
		(pad "4" smd rect
			(at -0.8001 -1.059942 270)
			(size 1.2192 1.4986)
			(layers "B.Cu" "B.Mask" "B.Paste")
			(net "GND")
		)
	)
	(footprint ""
		(layer "B.Cu")
		(at 111.379 -416.941 180)
		(property "Reference" "R4545"
			(at 0 0 0)
			(layer "B.SilkS")
			(hide yes)
			(effects
				(font
					(size 1.27 1.27)
				)
				(justify mirror)
			)
		)
		(property "Value" ""
			(at 0 0 0)
			(layer "B.Fab")
			(effects
				(font
					(size 1.27 1.27)
				)
				(justify mirror)
			)
		)
		(duplicate_pad_numbers_are_jumpers no)
		(fp_line
			(start 0.7874 0.4064)
			(end 0.7874 -0.4064)
			(stroke
				(width 0.1524)
				(type default)
			)
			(layer "B.SilkS")
		)
		(fp_line
			(start 0.7874 -0.4064)
			(end -0.7874 -0.4064)
			(stroke
				(width 0.1524)
				(type default)
			)
			(layer "B.SilkS")
		)
		(fp_line
			(start -0.7874 0.4064)
			(end 0.7874 0.4064)
			(stroke
				(width 0.1524)
				(type default)
			)
			(layer "B.SilkS")
		)
		(fp_line
			(start -0.7874 -0.4064)
			(end -0.7874 0.4064)
			(stroke
				(width 0.1524)
				(type default)
			)
			(layer "B.SilkS")
		)
		(fp_line
			(start 0.67945 0.3048)
			(end 0.67945 -0.305054)
			(stroke
				(width 0.1)
				(type default)
			)
			(layer "B.Fab")
		)
		(fp_line
			(start 0.67945 -0.305054)
			(end 0.12065 -0.305054)
			(stroke
				(width 0.1)
				(type default)
			)
			(layer "B.Fab")
		)
		(fp_line
			(start 0.12065 0.3048)
			(end 0.67945 0.3048)
			(stroke
				(width 0.1)
				(type default)
			)
			(layer "B.Fab")
		)
		(fp_line
			(start 0.12065 0.2794)
			(end 0.12065 0.3048)
			(stroke
				(width 0.1)
				(type default)
			)
			(layer "B.Fab")
		)
		(fp_line
			(start 0.12065 -0.2794)
			(end -0.12065 -0.2794)
			(stroke
				(width 0.1)
				(type default)
			)
			(layer "B.Fab")
		)
		(fp_line
			(start 0.12065 -0.305054)
			(end 0.12065 -0.2794)
			(stroke
				(width 0.1)
				(type default)
			)
			(layer "B.Fab")
		)
		(fp_line
			(start -0.120396 0.3048)
			(end -0.120396 0.2794)
			(stroke
				(width 0.1)
				(type default)
			)
			(layer "B.Fab")
		)
		(fp_line
			(start -0.120396 0.2794)
			(end 0.12065 0.2794)
			(stroke
				(width 0.1)
				(type default)
			)
			(layer "B.Fab")
		)
		(fp_line
			(start -0.12065 -0.2794)
			(end -0.12065 -0.3048)
			(stroke
				(width 0.1)
				(type default)
			)
			(layer "B.Fab")
		)
		(fp_line
			(start -0.12065 -0.3048)
			(end -0.67945 -0.3048)
			(stroke
				(width 0.1)
				(type default)
			)
			(layer "B.Fab")
		)
		(fp_line
			(start -0.67945 0.3048)
			(end -0.120396 0.3048)
			(stroke
				(width 0.1)
				(type default)
			)
			(layer "B.Fab")
		)
		(fp_line
			(start -0.67945 -0.3048)
			(end -0.67945 0.3048)
			(stroke
				(width 0.1)
				(type default)
			)
			(layer "B.Fab")
		)
		(pad "1" smd circle
			(at 0.40005 0)
			(size 0 0)
			(layers "B.Cu" "B.Mask" "B.Paste")
			(net "P3V3_AUX")
		)
		(pad "2" smd circle
			(at -0.40005 0)
			(size 0 0)
			(layers "B.Cu" "B.Mask" "B.Paste")
			(net "HGX_DETECT")
		)
	)
	(footprint ""
		(layer "B.Cu")
		(at 141.820646 -408.517344 90)
		(property "Reference" "C6741"
			(at 0 0 90)
			(layer "B.SilkS")
			(hide yes)
			(effects
				(font
					(size 1.27 1.27)
				)
				(justify mirror)
			)
		)
		(property "Value" ""
			(at 0 0 90)
			(layer "B.Fab")
			(effects
				(font
					(size 1.27 1.27)
				)
				(justify mirror)
			)
		)
		(duplicate_pad_numbers_are_jumpers no)
		(fp_line
			(start 0.299974 -0.150114)
			(end -0.299974 -0.150114)
			(stroke
				(width 0.1)
				(type default)
			)
			(layer "B.Fab")
		)
		(fp_line
			(start -0.299974 -0.150114)
			(end -0.299974 0.150114)
			(stroke
				(width 0.1)
				(type default)
			)
			(layer "B.Fab")
		)
		(fp_line
			(start 0.299974 0.150114)
			(end 0.299974 -0.150114)
			(stroke
				(width 0.1)
				(type default)
			)
			(layer "B.Fab")
		)
		(fp_line
			(start -0.299974 0.150114)
			(end 0.299974 0.150114)
			(stroke
				(width 0.1)
				(type default)
			)
			(layer "B.Fab")
		)
		(pad "1" smd rect
			(at 0.2667 0 270)
			(size 0.3048 0.381)
			(layers "B.Cu" "B.Mask" "B.Paste")
			(net "P5E_CPU1_P3_TX_BUF_C_DP<8>")
		)
		(pad "2" smd rect
			(at -0.2667 0 270)
			(size 0.3048 0.381)
			(layers "B.Cu" "B.Mask" "B.Paste")
			(net "P5E_CPU1_P3_TX_BUF_DP<8>")
		)
	)
	(footprint ""
		(layer "B.Cu")
		(at 231.775 -242.443 90)
		(property "Reference" "R324"
			(at 0 0 90)
			(layer "B.SilkS")
			(hide yes)
			(effects
				(font
					(size 1.27 1.27)
				)
				(justify mirror)
			)
		)
		(property "Value" ""
			(at 0 0 90)
			(layer "B.Fab")
			(effects
				(font
					(size 1.27 1.27)
				)
				(justify mirror)
			)
		)
		(duplicate_pad_numbers_are_jumpers no)
		(fp_line
			(start 0.7874 -0.4064)
			(end -0.7874 -0.4064)
			(stroke
				(width 0.1524)
				(type default)
			)
			(layer "B.SilkS")
		)
		(fp_line
			(start -0.7874 -0.4064)
			(end -0.7874 0.4064)
			(stroke
				(width 0.1524)
				(type default)
			)
			(layer "B.SilkS")
		)
		(fp_line
			(start 0.7874 0.4064)
			(end 0.7874 -0.4064)
			(stroke
				(width 0.1524)
				(type default)
			)
			(layer "B.SilkS")
		)
		(fp_line
			(start -0.7874 0.4064)
			(end 0.7874 0.4064)
			(stroke
				(width 0.1524)
				(type default)
			)
			(layer "B.SilkS")
		)
		(fp_line
			(start 0.67945 -0.305054)
			(end 0.12065 -0.305054)
			(stroke
				(width 0.1)
				(type default)
			)
			(layer "B.Fab")
		)
		(fp_line
			(start 0.12065 -0.305054)
			(end 0.12065 -0.2794)
			(stroke
				(width 0.1)
				(type default)
			)
			(layer "B.Fab")
		)
		(fp_line
			(start -0.12065 -0.3048)
			(end -0.67945 -0.3048)
			(stroke
				(width 0.1)
				(type default)
			)
			(layer "B.Fab")
		)
		(fp_line
			(start -0.67945 -0.3048)
			(end -0.67945 0.3048)
			(stroke
				(width 0.1)
				(type default)
			)
			(layer "B.Fab")
		)
		(fp_line
			(start 0.12065 -0.2794)
			(end -0.12065 -0.2794)
			(stroke
				(width 0.1)
				(type default)
			)
			(layer "B.Fab")
		)
		(fp_line
			(start -0.12065 -0.2794)
			(end -0.12065 -0.3048)
			(stroke
				(width 0.1)
				(type default)
			)
			(layer "B.Fab")
		)
		(fp_line
			(start 0.12065 0.2794)
			(end 0.12065 0.3048)
			(stroke
				(width 0.1)
				(type default)
			)
			(layer "B.Fab")
		)
		(fp_line
			(start -0.120396 0.2794)
			(end 0.12065 0.2794)
			(stroke
				(width 0.1)
				(type default)
			)
			(layer "B.Fab")
		)
		(fp_line
			(start 0.67945 0.3048)
			(end 0.67945 -0.305054)
			(stroke
				(width 0.1)
				(type default)
			)
			(layer "B.Fab")
		)
		(fp_line
			(start 0.12065 0.3048)
			(end 0.67945 0.3048)
			(stroke
				(width 0.1)
				(type default)
			)
			(layer "B.Fab")
		)
		(fp_line
			(start -0.120396 0.3048)
			(end -0.120396 0.2794)
			(stroke
				(width 0.1)
				(type default)
			)
			(layer "B.Fab")
		)
		(fp_line
			(start -0.67945 0.3048)
			(end -0.120396 0.3048)
			(stroke
				(width 0.1)
				(type default)
			)
			(layer "B.Fab")
		)
		(pad "1" smd rect
			(at 0.40005 0 90)
			(size 0.4572 0.508)
			(layers "B.Cu" "B.Mask" "B.Paste")
			(net "SMB_CPU0_CPU1_APML_SCL_R2")
		)
		(pad "2" smd rect
			(at -0.40005 0 90)
			(size 0.4572 0.508)
			(layers "B.Cu" "B.Mask" "B.Paste")
			(net "SMB_CPU0_CPU1_APML_MUX1_SCL")
		)
	)
	(footprint ""
		(layer "B.Cu")
		(at 380.218442 -396.393162 -90)
		(property "Reference" "C1005"
			(at 0 0 90)
			(layer "B.SilkS")
			(hide yes)
			(effects
				(font
					(size 1.27 1.27)
				)
				(justify mirror)
			)
		)
		(property "Value" ""
			(at 0 0 90)
			(layer "B.Fab")
			(effects
				(font
					(size 1.27 1.27)
				)
				(justify mirror)
			)
		)
		(duplicate_pad_numbers_are_jumpers no)
		(fp_line
			(start -0.299974 0.150114)
			(end 0.299974 0.150114)
			(stroke
				(width 0.1)
				(type default)
			)
			(layer "B.Fab")
		)
		(fp_line
			(start 0.299974 0.150114)
			(end 0.299974 -0.150114)
			(stroke
				(width 0.1)
				(type default)
			)
			(layer "B.Fab")
		)
		(fp_line
			(start -0.299974 -0.150114)
			(end -0.299974 0.150114)
			(stroke
				(width 0.1)
				(type default)
			)
			(layer "B.Fab")
		)
		(fp_line
			(start 0.299974 -0.150114)
			(end -0.299974 -0.150114)
			(stroke
				(width 0.1)
				(type default)
			)
			(layer "B.Fab")
		)
		(pad "1" smd rect
			(at 0.2667 0 90)
			(size 0.3048 0.381)
			(layers "B.Cu" "B.Mask" "B.Paste")
			(net "P1V8_CPU0_RT3_1A")
		)
		(pad "2" smd rect
			(at -0.2667 0 90)
			(size 0.3048 0.381)
			(layers "B.Cu" "B.Mask" "B.Paste")
			(net "GND")
		)
	)
	(footprint ""
		(layer "B.Cu")
		(at 319.322958 -203.917296 -90)
		(property "Reference" "R388"
			(at 0 0 90)
			(layer "B.SilkS")
			(hide yes)
			(effects
				(font
					(size 1.27 1.27)
				)
				(justify mirror)
			)
		)
		(property "Value" ""
			(at 0 0 90)
			(layer "B.Fab")
			(effects
				(font
					(size 1.27 1.27)
				)
				(justify mirror)
			)
		)
		(duplicate_pad_numbers_are_jumpers no)
		(fp_line
			(start -0.7874 0.4064)
			(end 0.7874 0.4064)
			(stroke
				(width 0.1524)
				(type default)
			)
			(layer "B.SilkS")
		)
		(fp_line
			(start 0.7874 0.4064)
			(end 0.7874 -0.4064)
			(stroke
				(width 0.1524)
				(type default)
			)
			(layer "B.SilkS")
		)
		(fp_line
			(start -0.7874 -0.4064)
			(end -0.7874 0.4064)
			(stroke
				(width 0.1524)
				(type default)
			)
			(layer "B.SilkS")
		)
		(fp_line
			(start 0.7874 -0.4064)
			(end -0.7874 -0.4064)
			(stroke
				(width 0.1524)
				(type default)
			)
			(layer "B.SilkS")
		)
		(fp_line
			(start -0.67945 0.3048)
			(end -0.120396 0.3048)
			(stroke
				(width 0.1)
				(type default)
			)
			(layer "B.Fab")
		)
		(fp_line
			(start -0.120396 0.3048)
			(end -0.120396 0.2794)
			(stroke
				(width 0.1)
				(type default)
			)
			(layer "B.Fab")
		)
		(fp_line
			(start 0.12065 0.3048)
			(end 0.67945 0.3048)
			(stroke
				(width 0.1)
				(type default)
			)
			(layer "B.Fab")
		)
		(fp_line
			(start 0.67945 0.3048)
			(end 0.67945 -0.305054)
			(stroke
				(width 0.1)
				(type default)
			)
			(layer "B.Fab")
		)
		(fp_line
			(start -0.120396 0.2794)
			(end 0.12065 0.2794)
			(stroke
				(width 0.1)
				(type default)
			)
			(layer "B.Fab")
		)
		(fp_line
			(start 0.12065 0.2794)
			(end 0.12065 0.3048)
			(stroke
				(width 0.1)
				(type default)
			)
			(layer "B.Fab")
		)
		(fp_line
			(start -0.12065 -0.2794)
			(end -0.12065 -0.3048)
			(stroke
				(width 0.1)
				(type default)
			)
			(layer "B.Fab")
		)
		(fp_line
			(start 0.12065 -0.2794)
			(end -0.12065 -0.2794)
			(stroke
				(width 0.1)
				(type default)
			)
			(layer "B.Fab")
		)
		(fp_line
			(start -0.67945 -0.3048)
			(end -0.67945 0.3048)
			(stroke
				(width 0.1)
				(type default)
			)
			(layer "B.Fab")
		)
		(fp_line
			(start -0.12065 -0.3048)
			(end -0.67945 -0.3048)
			(stroke
				(width 0.1)
				(type default)
			)
			(layer "B.Fab")
		)
		(fp_line
			(start 0.12065 -0.305054)
			(end 0.12065 -0.2794)
			(stroke
				(width 0.1)
				(type default)
			)
			(layer "B.Fab")
		)
		(fp_line
			(start 0.67945 -0.305054)
			(end 0.12065 -0.305054)
			(stroke
				(width 0.1)
				(type default)
			)
			(layer "B.Fab")
		)
		(pad "1" smd circle
			(at 0.40005 0 90)
			(size 0 0)
			(layers "B.Cu" "B.Mask" "B.Paste")
			(net "P3V3_AUX")
		)
		(pad "2" smd circle
			(at -0.40005 0 90)
			(size 0 0)
			(layers "B.Cu" "B.Mask" "B.Paste")
			(net "CPU0_CORETYPE1")
		)
	)
	(footprint ""
		(layer "B.Cu")
		(at 372.135654 -269.30731 180)
		(property "Reference" "C2251"
			(at 0 0 0)
			(layer "B.SilkS")
			(hide yes)
			(effects
				(font
					(size 1.27 1.27)
				)
				(justify mirror)
			)
		)
		(property "Value" ""
			(at 0 0 0)
			(layer "B.Fab")
			(effects
				(font
					(size 1.27 1.27)
				)
				(justify mirror)
			)
		)
		(duplicate_pad_numbers_are_jumpers no)
		(fp_line
			(start 0.7874 0.4064)
			(end 0.7874 -0.4064)
			(stroke
				(width 0.1524)
				(type default)
			)
			(layer "B.SilkS")
		)
		(fp_line
			(start 0.7874 -0.4064)
			(end -0.7874 -0.4064)
			(stroke
				(width 0.1524)
				(type default)
			)
			(layer "B.SilkS")
		)
		(fp_line
			(start -0.7874 0.4064)
			(end 0.7874 0.4064)
			(stroke
				(width 0.1524)
				(type default)
			)
			(layer "B.SilkS")
		)
		(fp_line
			(start -0.7874 -0.4064)
			(end -0.7874 0.4064)
			(stroke
				(width 0.1524)
				(type default)
			)
			(layer "B.SilkS")
		)
		(fp_line
			(start 0.67945 0.3048)
			(end 0.67945 -0.305054)
			(stroke
				(width 0.1)
				(type default)
			)
			(layer "B.Fab")
		)
		(fp_line
			(start 0.67945 -0.305054)
			(end 0.12065 -0.305054)
			(stroke
				(width 0.1)
				(type default)
			)
			(layer "B.Fab")
		)
		(fp_line
			(start 0.12065 0.3048)
			(end 0.67945 0.3048)
			(stroke
				(width 0.1)
				(type default)
			)
			(layer "B.Fab")
		)
		(fp_line
			(start 0.12065 0.2794)
			(end 0.12065 0.3048)
			(stroke
				(width 0.1)
				(type default)
			)
			(layer "B.Fab")
		)
		(fp_line
			(start 0.12065 -0.2794)
			(end -0.12065 -0.2794)
			(stroke
				(width 0.1)
				(type default)
			)
			(layer "B.Fab")
		)
		(fp_line
			(start 0.12065 -0.305054)
			(end 0.12065 -0.2794)
			(stroke
				(width 0.1)
				(type default)
			)
			(layer "B.Fab")
		)
		(fp_line
			(start -0.120396 0.3048)
			(end -0.120396 0.2794)
			(stroke
				(width 0.1)
				(type default)
			)
			(layer "B.Fab")
		)
		(fp_line
			(start -0.120396 0.2794)
			(end 0.12065 0.2794)
			(stroke
				(width 0.1)
				(type default)
			)
			(layer "B.Fab")
		)
		(fp_line
			(start -0.12065 -0.2794)
			(end -0.12065 -0.3048)
			(stroke
				(width 0.1)
				(type default)
			)
			(layer "B.Fab")
		)
		(fp_line
			(start -0.12065 -0.3048)
			(end -0.67945 -0.3048)
			(stroke
				(width 0.1)
				(type default)
			)
			(layer "B.Fab")
		)
		(fp_line
			(start -0.67945 0.3048)
			(end -0.120396 0.3048)
			(stroke
				(width 0.1)
				(type default)
			)
			(layer "B.Fab")
		)
		(fp_line
			(start -0.67945 -0.3048)
			(end -0.67945 0.3048)
			(stroke
				(width 0.1)
				(type default)
			)
			(layer "B.Fab")
		)
		(pad "1" smd circle
			(at 0.40005 0)
			(size 0 0)
			(layers "B.Cu" "B.Mask" "B.Paste")
			(net "PVDDCR_CPU1_P0")
		)
		(pad "2" smd circle
			(at -0.40005 0)
			(size 0 0)
			(layers "B.Cu" "B.Mask" "B.Paste")
			(net "GND")
		)
	)
	(footprint ""
		(layer "B.Cu")
		(at 28.657804 -388.654036 90)
		(property "Reference" "PC6635_2"
			(at 0 0 90)
			(layer "B.SilkS")
			(hide yes)
			(effects
				(font
					(size 1.27 1.27)
				)
				(justify mirror)
			)
		)
		(property "Value" ""
			(at 0 0 90)
			(layer "B.Fab")
			(effects
				(font
					(size 1.27 1.27)
				)
				(justify mirror)
			)
		)
		(duplicate_pad_numbers_are_jumpers no)
		(fp_line
			(start 1.524 -0.762)
			(end -1.524 -0.762)
			(stroke
				(width 0.1524)
				(type default)
			)
			(layer "B.SilkS")
		)
		(fp_line
			(start -1.524 -0.762)
			(end -1.524 0.762)
			(stroke
				(width 0.1524)
				(type default)
			)
			(layer "B.SilkS")
		)
		(fp_line
			(start 1.524 0.762)
			(end 1.524 -0.762)
			(stroke
				(width 0.1524)
				(type default)
			)
			(layer "B.SilkS")
		)
		(fp_line
			(start -1.524 0.762)
			(end 1.524 0.762)
			(stroke
				(width 0.1524)
				(type default)
			)
			(layer "B.SilkS")
		)
		(fp_line
			(start 1.1049 -0.724916)
			(end 1.1049 0.724916)
			(stroke
				(width 0.1)
				(type default)
			)
			(layer "B.Fab")
		)
		(fp_line
			(start -1.1049 -0.724916)
			(end 1.1049 -0.724916)
			(stroke
				(width 0.1)
				(type default)
			)
			(layer "B.Fab")
		)
		(fp_line
			(start 1.1049 0.724916)
			(end -1.1049 0.724916)
			(stroke
				(width 0.1)
				(type default)
			)
			(layer "B.Fab")
		)
		(fp_line
			(start -1.1049 0.724916)
			(end -1.1049 -0.724916)
			(stroke
				(width 0.1)
				(type default)
			)
			(layer "B.Fab")
		)
		(pad "1" smd rect
			(at 0.889 0 90)
			(size 1.016 1.27)
			(layers "B.Cu" "B.Mask" "B.Paste")
			(net "SW_P12V_AUX_P0V9_RETIMER_CPU1_FLT")
		)
		(pad "2" smd rect
			(at -0.889 0 90)
			(size 1.016 1.27)
			(layers "B.Cu" "B.Mask" "B.Paste")
			(net "GND")
		)
	)
)
